# T6G (Grand Teton) — schematic netlist excerpt (pin names and nets, part order shuffled) for the footprints in the layout excerpt that follows; sources: Cadence DE-HDL packaged netlist, KiCad conversion of 04192023_DAF0TMB3IC0_F0TG_MB_C_brd_V02_OCP.brd

R1296  Q_RES  0 5% CHIP  pkg 0402LF  page 159 : A = I3C_SPD_DDRGL_CPU1_SDA ; B = I3C_SPD_DDRGL_CPU1_LVC1_SDA

(kicad_pcb
	(version 20260206)
	(generator "pcbnew")
	(generator_version "10.0")
	(general
		(thickness 1.6)
		(legacy_teardrops no)
	)
	(paper "A4")
	(title_block
		(title "04192023_DAF0TMB3IC0_F0TG_MB_C_brd_V02_OCP.brd")
		(comment 1 "Grand Teton / footprints 1100-1100 of 8354")
	)
	(layers
		(0 "F.Cu" signal "TOP")
		(4 "In1.Cu" signal "GND")
		(6 "In2.Cu" signal "IN1")
		(8 "In3.Cu" signal "GND1")
		(10 "In4.Cu" signal "IN2")
		(12 "In5.Cu" signal "GND2")
		(14 "In6.Cu" signal "IN3")
		(16 "In7.Cu" signal "GND3")
		(18 "In8.Cu" signal "VCC")
		(20 "In9.Cu" signal "VCC1")
		(22 "In10.Cu" signal "GND4")
		(24 "In11.Cu" signal "IN4")
		(26 "In12.Cu" signal "GND5")
		(28 "In13.Cu" signal "IN5")
		(30 "In14.Cu" signal "GND6")
		(32 "In15.Cu" signal "IN6")
		(34 "In16.Cu" signal "GND7")
		(2 "B.Cu" signal "BOTTOM")
		(9 "F.Adhes" user "F.Adhesive")
		(11 "B.Adhes" user "B.Adhesive")
		(13 "F.Paste" user "Package Geometry/Pastemask Top")
		(15 "B.Paste" user "Package Geometry/Pastemask Bottom")
		(5 "F.SilkS" user "Ref Des/Silkscreen Top")
		(7 "B.SilkS" user "Ref Des/Silkscreen Bottom")
		(1 "F.Mask" user "Board Geometry/Soldermask Top")
		(3 "B.Mask" user "Board Geometry/Soldermask Bottom")
		(17 "Dwgs.User" user "User.Drawings")
		(19 "Cmts.User" user "User.Comments")
		(21 "Eco1.User" user "User.Eco1")
		(23 "Eco2.User" user "User.Eco2")
		(25 "Edge.Cuts" user "Board Geometry/Outline")
		(27 "Margin" user)
		(31 "F.CrtYd" user "Package Geometry/Place Bound Top")
		(29 "B.CrtYd" user "Package Geometry/Place Bound Bottom")
		(35 "F.Fab" user "Ref Des/Assembly Top")
		(33 "B.Fab" user "Ref Des/Assembly Bottom")
	)
	(footprint ""
		(layer "F.Cu")
		(at 184.455054 -168.317926 -90)
		(property "Reference" "R1296"
			(at 0 0 270)
			(layer "F.SilkS")
			(hide yes)
			(effects
				(font
					(size 1.27 1.27)
				)
			)
		)
		(property "Value" ""
			(at 0 0 270)
			(layer "F.Fab")
			(effects
				(font
					(size 1.27 1.27)
				)
			)
		)
		(duplicate_pad_numbers_are_jumpers no)
		(fp_line
			(start -0.7874 0.4064)
			(end -0.7874 -0.4064)
			(stroke
				(width 0.1524)
				(type default)
			)
			(layer "F.SilkS")
		)
		(fp_line
			(start 0.7874 0.4064)
			(end -0.7874 0.4064)
			(stroke
				(width 0.1524)
				(type default)
			)
			(layer "F.SilkS")
		)
		(fp_line
			(start -0.7874 -0.4064)
			(end 0.7874 -0.4064)
			(stroke
				(width 0.1524)
				(type default)
			)
			(layer "F.SilkS")
		)
		(fp_line
			(start 0.7874 -0.4064)
			(end 0.7874 0.4064)
			(stroke
				(width 0.1524)
				(type default)
			)
			(layer "F.SilkS")
		)
		(fp_line
			(start -0.67945 0.3048)
			(end -0.67945 -0.305054)
			(stroke
				(width 0.1)
				(type default)
			)
			(layer "F.Fab")
		)
		(fp_line
			(start -0.12065 0.3048)
			(end -0.67945 0.3048)
			(stroke
				(width 0.1)
				(type default)
			)
			(layer "F.Fab")
		)
		(fp_line
			(start 0.120396 0.3048)
			(end 0.120396 0.2794)
			(stroke
				(width 0.1)
				(type default)
			)
			(layer "F.Fab")
		)
		(fp_line
			(start 0.67945 0.3048)
			(end 0.120396 0.3048)
			(stroke
				(width 0.1)
				(type default)
			)
			(layer "F.Fab")
		)
		(fp_line
			(start -0.12065 0.2794)
			(end -0.12065 0.3048)
			(stroke
				(width 0.1)
				(type default)
			)
			(layer "F.Fab")
		)
		(fp_line
			(start 0.120396 0.2794)
			(end -0.12065 0.2794)
			(stroke
				(width 0.1)
				(type default)
			)
			(layer "F.Fab")
		)
		(fp_line
			(start -0.12065 -0.2794)
			(end 0.12065 -0.2794)
			(stroke
				(width 0.1)
				(type default)
			)
			(layer "F.Fab")
		)
		(fp_line
			(start 0.12065 -0.2794)
			(end 0.12065 -0.3048)
			(stroke
				(width 0.1)
				(type default)
			)
			(layer "F.Fab")
		)
		(fp_line
			(start 0.12065 -0.3048)
			(end 0.67945 -0.3048)
			(stroke
				(width 0.1)
				(type default)
			)
			(layer "F.Fab")
		)
		(fp_line
			(start 0.67945 -0.3048)
			(end 0.67945 0.3048)
			(stroke
				(width 0.1)
				(type default)
			)
			(layer "F.Fab")
		)
		(fp_line
			(start -0.67945 -0.305054)
			(end -0.12065 -0.305054)
			(stroke
				(width 0.1)
				(type default)
			)
			(layer "F.Fab")
		)
		(fp_line
			(start -0.12065 -0.305054)
			(end -0.12065 -0.2794)
			(stroke
				(width 0.1)
				(type default)
			)
			(layer "F.Fab")
		)
		(pad "1" smd rect
			(at -0.40005 0 90)
			(size 0.4572 0.508)
			(layers "F.Cu" "F.Mask" "F.Paste")
			(net "I3C_SPD_DDRGL_CPU1_SDA")
		)
		(pad "2" smd rect
			(at 0.40005 0 90)
			(size 0.4572 0.508)
			(layers "F.Cu" "F.Mask" "F.Paste")
			(net "I3C_SPD_DDRGL_CPU1_LVC1_SDA")
		)
	)
)
